(kicad_pcb
	(version 20260206)
	(generator "pcbnew")
	(generator_version "10.0")
	(general
		(thickness 1.6)
		(legacy_teardrops no)
	)
	(paper "A4")
	(title_block
		(title "v1-chassis-manager — T6M_CM_d_v01_1031_1645.brd")
		(comment 1 "Open CloudServer (Microsoft) / footprints 1428-1437 of 2512")
	)
	(layers
		(0 "F.Cu" signal "TOP")
		(4 "In1.Cu" signal "GND1")
		(6 "In2.Cu" signal "IN1")
		(8 "In3.Cu" signal "VCC1")
		(10 "In4.Cu" signal "VCC2")
		(12 "In5.Cu" signal "GND2")
		(14 "In6.Cu" signal "IN2")
		(16 "In7.Cu" signal "IN3")
		(18 "In8.Cu" signal "GND3")
		(2 "B.Cu" signal "BOTTOM")
		(9 "F.Adhes" user "F.Adhesive")
		(11 "B.Adhes" user "B.Adhesive")
		(13 "F.Paste" user "Package Geometry/Pastemask Top")
		(15 "B.Paste" user "Package Geometry/Pastemask Bottom")
		(5 "F.SilkS" user "Ref Des/Silkscreen Top")
		(7 "B.SilkS" user "Ref Des/Silkscreen Bottom")
		(1 "F.Mask" user "Board Geometry/Soldermask Top")
		(3 "B.Mask" user "Board Geometry/Soldermask Bottom")
		(17 "Dwgs.User" user "User.Drawings")
		(19 "Cmts.User" user "User.Comments")
		(21 "Eco1.User" user "User.Eco1")
		(23 "Eco2.User" user "User.Eco2")
		(25 "Edge.Cuts" user "Board Geometry/Outline")
		(27 "Margin" user)
		(31 "F.CrtYd" user "Package Geometry/Place Bound Top")
		(29 "B.CrtYd" user "Package Geometry/Place Bound Bottom")
		(35 "F.Fab" user "Ref Des/Assembly Top")
		(33 "B.Fab" user "Ref Des/Assembly Bottom")
	)
	(footprint ""
		(layer "F.Cu")
		(at 47.418244 -106.40695 180)
		(property "Reference" "PC26"
			(at 0.202692 -2.089658 0)
			(unlocked yes)
			(layer "F.SilkS")
			(effects
				(font
					(size 0.7874 0.5842)
					(thickness 0.1524)
				)
				(justify left)
			)
		)
		(property "Value" ""
			(at 0 0 180)
			(layer "F.Fab")
			(effects
				(font
					(size 1.27 1.27)
				)
			)
		)
		(duplicate_pad_numbers_are_jumpers no)
		(fp_line
			(start 0.7874 0.4064)
			(end -0.7874 0.4064)
			(stroke
				(width 0.1524)
				(type default)
			)
			(layer "F.SilkS")
		)
		(fp_line
			(start 0.7874 -0.4064)
			(end 0.7874 0.4064)
			(stroke
				(width 0.1524)
				(type default)
			)
			(layer "F.SilkS")
		)
		(fp_line
			(start 0 0.381)
			(end 0 -0.381)
			(stroke
				(width 0.1524)
				(type default)
			)
			(layer "F.SilkS")
		)
		(fp_line
			(start -0.7874 0.4064)
			(end -0.7874 -0.4064)
			(stroke
				(width 0.1524)
				(type default)
			)
			(layer "F.SilkS")
		)
		(fp_line
			(start -0.7874 -0.4064)
			(end 0.7874 -0.4064)
			(stroke
				(width 0.1524)
				(type default)
			)
			(layer "F.SilkS")
		)
		(fp_poly
			(pts
				(xy -0.5334 0.254) (xy -0.635 0.254) (xy -0.635 0.2286) (xy -0.635 -0.254) (xy -0.5334 -0.254) (xy -0.5334 -0.2794)
				(xy 0.5334 -0.2794) (xy 0.5334 -0.254) (xy 0.635 -0.254) (xy 0.635 0.254) (xy 0.5334 0.254) (xy 0.5334 0.2794)
				(xy -0.508 0.2794) (xy -0.5334 0.2794)
			)
			(stroke
				(width 0)
				(type default)
			)
			(fill no)
			(layer "F.CrtYd")
		)
		(pad "1" smd rect
			(at 0.40005 0 180)
			(size 0.4572 0.508)
			(layers "F.Cu" "F.Mask" "F.Paste")
			(net "PWRGD_NODE1_P5V_STB_PG")
		)
		(pad "2" smd rect
			(at -0.40005 0 180)
			(size 0.4572 0.508)
			(layers "F.Cu" "F.Mask" "F.Paste")
			(net "GND")
		)
	)
	(footprint ""
		(layer "F.Cu")
		(at 86.914228 -133.213094 -90)
		(property "Reference" "D35"
			(at -3.52552 -0.706374 90)
			(unlocked yes)
			(layer "F.SilkS")
			(effects
				(font
					(size 0.7874 0.5842)
					(thickness 0.1524)
				)
				(justify left)
			)
		)
		(property "Value" ""
			(at 0 0 270)
			(layer "F.Fab")
			(effects
				(font
					(size 1.27 1.27)
				)
			)
		)
		(duplicate_pad_numbers_are_jumpers no)
		(fp_line
			(start -1.3208 0.5588)
			(end -1.3208 -0.5588)
			(stroke
				(width 0.1524)
				(type default)
			)
			(layer "F.SilkS")
		)
		(fp_line
			(start 1.3208 0.5588)
			(end -1.3208 0.5588)
			(stroke
				(width 0.1524)
				(type default)
			)
			(layer "F.SilkS")
		)
		(fp_line
			(start 1.6256 0.5588)
			(end 1.6256 -0.5588)
			(stroke
				(width 0.1524)
				(type default)
			)
			(layer "F.SilkS")
		)
		(fp_line
			(start 1.778 0.5588)
			(end 1.3208 0.5588)
			(stroke
				(width 0.1524)
				(type default)
			)
			(layer "F.SilkS")
		)
		(fp_line
			(start -1.3208 -0.5588)
			(end 1.3208 -0.5588)
			(stroke
				(width 0.1524)
				(type default)
			)
			(layer "F.SilkS")
		)
		(fp_line
			(start 1.3208 -0.5588)
			(end 1.3208 0.5588)
			(stroke
				(width 0.1524)
				(type default)
			)
			(layer "F.SilkS")
		)
		(fp_line
			(start 1.4732 -0.5588)
			(end 1.4732 0.5588)
			(stroke
				(width 0.1524)
				(type default)
			)
			(layer "F.SilkS")
		)
		(fp_line
			(start 1.778 -0.5588)
			(end 1.778 0.5588)
			(stroke
				(width 0.1524)
				(type default)
			)
			(layer "F.SilkS")
		)
		(fp_line
			(start 1.778 -0.5588)
			(end 1.3208 -0.5588)
			(stroke
				(width 0.1524)
				(type default)
			)
			(layer "F.SilkS")
		)
		(fp_circle
			(center 2.4384 0)
			(end 2.4384 -0.413512)
			(stroke
				(width 0.1524)
				(type default)
			)
			(fill no)
			(layer "F.SilkS")
		)
		(fp_rect
			(start -1.1684 0.508)
			(end 1.1684 -0.508)
			(stroke
				(width 0)
				(type default)
			)
			(fill no)
			(layer "F.CrtYd")
		)
		(fp_text user "-"
			(at 2.350008 0.57912 270)
			(unlocked yes)
			(layer "F.SilkS")
			(effects
				(font
					(size 0.7874 0.5842)
					(thickness 0.1524)
				)
				(justify left)
			)
		)
		(pad "A" smd rect
			(at -0.750062 0 270)
			(size 0.8128 0.8128)
			(layers "F.Cu" "F.Mask" "F.Paste")
			(net "P3V3_NODE1")
		)
		(pad "C" smd rect
			(at 0.750062 0 270)
			(size 0.8128 0.8128)
			(layers "F.Cu" "F.Mask" "F.Paste")
			(net "N53313513")
		)
	)
	(footprint ""
		(layer "F.Cu")
		(at 74.394822 -17.664176 90)
		(property "Reference" "C177"
			(at -3.058414 6.144514 90)
			(unlocked yes)
			(layer "F.SilkS")
			(effects
				(font
					(size 0.7874 0.5842)
					(thickness 0.1524)
				)
			)
		)
		(property "Value" ""
			(at 0 0 90)
			(layer "F.Fab")
			(effects
				(font
					(size 1.27 1.27)
				)
			)
		)
		(duplicate_pad_numbers_are_jumpers no)
		(fp_line
			(start 1.2954 -0.5842)
			(end 1.2954 0.5842)
			(stroke
				(width 0.1524)
				(type default)
			)
			(layer "F.SilkS")
		)
		(fp_line
			(start 0 -0.5842)
			(end 0 0.5842)
			(stroke
				(width 0.1524)
				(type default)
			)
			(layer "F.SilkS")
		)
		(fp_line
			(start -1.2954 -0.5842)
			(end 1.2954 -0.5842)
			(stroke
				(width 0.1524)
				(type default)
			)
			(layer "F.SilkS")
		)
		(fp_line
			(start 1.2954 0.5842)
			(end -1.2954 0.5842)
			(stroke
				(width 0.1524)
				(type default)
			)
			(layer "F.SilkS")
		)
		(fp_line
			(start -1.2954 0.5842)
			(end -1.2954 -0.5842)
			(stroke
				(width 0.1524)
				(type default)
			)
			(layer "F.SilkS")
		)
		(fp_poly
			(pts
				(xy 0.8636 -0.4572) (xy 0.8636 -0.3556) (xy 1.143 -0.3556) (xy 1.143 0.3556) (xy 0.8636 0.3556)
				(xy 0.8636 0.4572) (xy -0.8636 0.4572) (xy -0.8636 0.3556) (xy -1.143 0.3556) (xy -1.143 -0.3556)
				(xy -0.8636 -0.3556) (xy -0.8636 -0.4572)
			)
			(stroke
				(width 0)
				(type default)
			)
			(fill no)
			(layer "F.CrtYd")
		)
		(fp_line
			(start 0.884936 -0.504952)
			(end 0.884936 0.504952)
			(stroke
				(width 0.1)
				(type default)
			)
			(layer "F.Fab")
		)
		(fp_line
			(start -0.884936 -0.504952)
			(end 0.884936 -0.504952)
			(stroke
				(width 0.1)
				(type default)
			)
			(layer "F.Fab")
		)
		(fp_line
			(start 0.884936 0.504952)
			(end -0.884936 0.504952)
			(stroke
				(width 0.1)
				(type default)
			)
			(layer "F.Fab")
		)
		(fp_line
			(start -0.884936 0.504952)
			(end -0.884936 -0.504952)
			(stroke
				(width 0.1)
				(type default)
			)
			(layer "F.Fab")
		)
		(pad "1" smd rect
			(at 0.7366 0 180)
			(size 0.7112 0.8128)
			(layers "F.Cu" "F.Mask" "F.Paste")
			(net "PV_VDDR_NODE1")
		)
		(pad "2" smd rect
			(at -0.7366 0 180)
			(size 0.7112 0.8128)
			(layers "F.Cu" "F.Mask" "F.Paste")
			(net "GND")
		)
	)
	(footprint ""
		(layer "F.Cu")
		(at 186.131708 -128.029716)
		(property "Reference" "R1286"
			(at 4.114292 19.725386 0)
			(unlocked yes)
			(layer "F.SilkS")
			(effects
				(font
					(size 0.7874 0.5842)
					(thickness 0.1524)
				)
				(justify left)
			)
		)
		(property "Value" ""
			(at 0 0 0)
			(layer "F.Fab")
			(effects
				(font
					(size 1.27 1.27)
				)
			)
		)
		(duplicate_pad_numbers_are_jumpers no)
		(fp_line
			(start -0.7874 -0.4064)
			(end 0.7874 -0.4064)
			(stroke
				(width 0.1524)
				(type default)
			)
			(layer "F.SilkS")
		)
		(fp_line
			(start -0.7874 0.4064)
			(end -0.7874 -0.4064)
			(stroke
				(width 0.1524)
				(type default)
			)
			(layer "F.SilkS")
		)
		(fp_line
			(start 0.7874 -0.4064)
			(end 0.7874 0.4064)
			(stroke
				(width 0.1524)
				(type default)
			)
			(layer "F.SilkS")
		)
		(fp_line
			(start 0.7874 0.4064)
			(end -0.7874 0.4064)
			(stroke
				(width 0.1524)
				(type default)
			)
			(layer "F.SilkS")
		)
		(fp_poly
			(pts
				(xy -0.508 0.2794) (xy -0.508 0.2286) (xy -0.635 0.2286) (xy -0.635 -0.254) (xy -0.5334 -0.254)
				(xy -0.5334 -0.2794) (xy 0.5334 -0.2794) (xy 0.5334 -0.254) (xy 0.635 -0.254) (xy 0.635 0.254) (xy 0.5334 0.254)
				(xy 0.5334 0.2794)
			)
			(stroke
				(width 0)
				(type default)
			)
			(fill no)
			(layer "F.CrtYd")
		)
		(pad "1" smd rect
			(at 0.40005 0)
			(size 0.4572 0.508)
			(layers "F.Cu" "F.Mask" "F.Paste")
			(net "SIO_JTAG_CPLD1_TDO")
		)
		(pad "2" smd rect
			(at -0.40005 0)
			(size 0.4572 0.508)
			(layers "F.Cu" "F.Mask" "F.Paste")
			(net "JTAG_CPLD1_TDO")
		)
	)
	(footprint ""
		(layer "F.Cu")
		(at 35.669728 -82.179922)
		(property "Reference" "R44"
			(at -4.58851 0.037338 0)
			(unlocked yes)
			(layer "F.SilkS")
			(effects
				(font
					(size 0.7874 0.5842)
					(thickness 0.1524)
				)
				(justify left)
			)
		)
		(property "Value" ""
			(at 0 0 0)
			(layer "F.Fab")
			(effects
				(font
					(size 1.27 1.27)
				)
			)
		)
		(duplicate_pad_numbers_are_jumpers no)
		(fp_line
			(start -0.7874 -0.4064)
			(end 0.7874 -0.4064)
			(stroke
				(width 0.1524)
				(type default)
			)
			(layer "F.SilkS")
		)
		(fp_line
			(start -0.7874 0.4064)
			(end -0.7874 -0.4064)
			(stroke
				(width 0.1524)
				(type default)
			)
			(layer "F.SilkS")
		)
		(fp_line
			(start 0.7874 -0.4064)
			(end 0.7874 0.4064)
			(stroke
				(width 0.1524)
				(type default)
			)
			(layer "F.SilkS")
		)
		(fp_line
			(start 0.7874 0.4064)
			(end -0.7874 0.4064)
			(stroke
				(width 0.1524)
				(type default)
			)
			(layer "F.SilkS")
		)
		(fp_poly
			(pts
				(xy -0.508 0.2794) (xy -0.508 0.2286) (xy -0.635 0.2286) (xy -0.635 -0.254) (xy -0.5334 -0.254)
				(xy -0.5334 -0.2794) (xy 0.5334 -0.2794) (xy 0.5334 -0.254) (xy 0.635 -0.254) (xy 0.635 0.254) (xy 0.5334 0.254)
				(xy 0.5334 0.2794)
			)
			(stroke
				(width 0)
				(type default)
			)
			(fill no)
			(layer "F.CrtYd")
		)
		(pad "1" smd rect
			(at 0.40005 0)
			(size 0.4572 0.508)
			(layers "F.Cu" "F.Mask" "F.Paste")
			(net "PD_CPU_NODE1_RP2_PERN")
		)
		(pad "2" smd rect
			(at -0.40005 0)
			(size 0.4572 0.508)
			(layers "F.Cu" "F.Mask" "F.Paste")
			(net "GND")
		)
	)
	(footprint ""
		(layer "F.Cu")
		(at 113.47831 -133.735572)
		(property "Reference" "PC101"
			(at 5.35051 -2.894076 0)
			(unlocked yes)
			(layer "F.SilkS")
			(effects
				(font
					(size 0.635 0.4064)
					(thickness 0.1524)
				)
				(justify left)
			)
		)
		(property "Value" ""
			(at 0 0 0)
			(layer "F.Fab")
			(effects
				(font
					(size 1.27 1.27)
				)
			)
		)
		(duplicate_pad_numbers_are_jumpers no)
		(fp_line
			(start -0.7874 -0.4064)
			(end 0.7874 -0.4064)
			(stroke
				(width 0.1524)
				(type default)
			)
			(layer "F.SilkS")
		)
		(fp_line
			(start -0.7874 0.4064)
			(end -0.7874 -0.4064)
			(stroke
				(width 0.1524)
				(type default)
			)
			(layer "F.SilkS")
		)
		(fp_line
			(start 0 0.381)
			(end 0 -0.381)
			(stroke
				(width 0.1524)
				(type default)
			)
			(layer "F.SilkS")
		)
		(fp_line
			(start 0.7874 -0.4064)
			(end 0.7874 0.4064)
			(stroke
				(width 0.1524)
				(type default)
			)
			(layer "F.SilkS")
		)
		(fp_line
			(start 0.7874 0.4064)
			(end -0.7874 0.4064)
			(stroke
				(width 0.1524)
				(type default)
			)
			(layer "F.SilkS")
		)
		(fp_poly
			(pts
				(xy -0.5334 0.254) (xy -0.635 0.254) (xy -0.635 0.2286) (xy -0.635 -0.254) (xy -0.5334 -0.254) (xy -0.5334 -0.2794)
				(xy 0.5334 -0.2794) (xy 0.5334 -0.254) (xy 0.635 -0.254) (xy 0.635 0.254) (xy 0.5334 0.254) (xy 0.5334 0.2794)
				(xy -0.508 0.2794) (xy -0.5334 0.2794)
			)
			(stroke
				(width 0)
				(type default)
			)
			(fill no)
			(layer "F.CrtYd")
		)
		(pad "1" smd rect
			(at 0.40005 0)
			(size 0.4572 0.508)
			(layers "F.Cu" "F.Mask" "F.Paste")
			(net "AGND_PVCCP_NODE1")
		)
		(pad "2" smd rect
			(at -0.40005 0)
			(size 0.4572 0.508)
			(layers "F.Cu" "F.Mask" "F.Paste")
			(net "ISENSE_PVCCP_NODE1_ISEN1N")
		)
	)
	(footprint ""
		(layer "F.Cu")
		(at 111.87176 -170.593512 180)
		(property "Reference" "R666"
			(at 2.02438 10.473436 0)
			(unlocked yes)
			(layer "F.SilkS")
			(effects
				(font
					(size 0.7874 0.5842)
					(thickness 0.1524)
				)
				(justify left)
			)
		)
		(property "Value" ""
			(at 0 0 180)
			(layer "F.Fab")
			(effects
				(font
					(size 1.27 1.27)
				)
			)
		)
		(duplicate_pad_numbers_are_jumpers no)
		(fp_line
			(start 0.7874 0.4064)
			(end -0.7874 0.4064)
			(stroke
				(width 0.1524)
				(type default)
			)
			(layer "F.SilkS")
		)
		(fp_line
			(start 0.7874 -0.4064)
			(end 0.7874 0.4064)
			(stroke
				(width 0.1524)
				(type default)
			)
			(layer "F.SilkS")
		)
		(fp_line
			(start -0.7874 0.4064)
			(end -0.7874 -0.4064)
			(stroke
				(width 0.1524)
				(type default)
			)
			(layer "F.SilkS")
		)
		(fp_line
			(start -0.7874 -0.4064)
			(end 0.7874 -0.4064)
			(stroke
				(width 0.1524)
				(type default)
			)
			(layer "F.SilkS")
		)
		(fp_poly
			(pts
				(xy -0.508 0.2794) (xy -0.508 0.2286) (xy -0.635 0.2286) (xy -0.635 -0.254) (xy -0.5334 -0.254)
				(xy -0.5334 -0.2794) (xy 0.5334 -0.2794) (xy 0.5334 -0.254) (xy 0.635 -0.254) (xy 0.635 0.254) (xy 0.5334 0.254)
				(xy 0.5334 0.2794)
			)
			(stroke
				(width 0)
				(type default)
			)
			(fill no)
			(layer "F.CrtYd")
		)
		(pad "1" smd rect
			(at 0.40005 0 180)
			(size 0.4572 0.508)
			(layers "F.Cu" "F.Mask" "F.Paste")
			(net "P3V3_NODE1")
		)
		(pad "2" smd rect
			(at -0.40005 0 180)
			(size 0.4572 0.508)
			(layers "F.Cu" "F.Mask" "F.Paste")
			(net "I2C_PSU1_SDA_MOS")
		)
	)
	(footprint ""
		(layer "F.Cu")
		(at 59.586368 -170.604688)
		(property "Reference" "C616"
			(at -9.464294 131.044696 0)
			(unlocked yes)
			(layer "F.SilkS")
			(effects
				(font
					(size 0.7874 0.5842)
					(thickness 0.1524)
				)
				(justify left)
			)
		)
		(property "Value" ""
			(at 0 0 0)
			(layer "F.Fab")
			(effects
				(font
					(size 1.27 1.27)
				)
			)
		)
		(duplicate_pad_numbers_are_jumpers no)
		(fp_line
			(start -0.7874 -0.4064)
			(end 0.7874 -0.4064)
			(stroke
				(width 0.1524)
				(type default)
			)
			(layer "F.SilkS")
		)
		(fp_line
			(start -0.7874 0.4064)
			(end -0.7874 -0.4064)
			(stroke
				(width 0.1524)
				(type default)
			)
			(layer "F.SilkS")
		)
		(fp_line
			(start 0 0.381)
			(end 0 -0.381)
			(stroke
				(width 0.1524)
				(type default)
			)
			(layer "F.SilkS")
		)
		(fp_line
			(start 0.7874 -0.4064)
			(end 0.7874 0.4064)
			(stroke
				(width 0.1524)
				(type default)
			)
			(layer "F.SilkS")
		)
		(fp_line
			(start 0.7874 0.4064)
			(end -0.7874 0.4064)
			(stroke
				(width 0.1524)
				(type default)
			)
			(layer "F.SilkS")
		)
		(fp_poly
			(pts
				(xy -0.5334 0.254) (xy -0.635 0.254) (xy -0.635 0.2286) (xy -0.635 -0.254) (xy -0.5334 -0.254) (xy -0.5334 -0.2794)
				(xy 0.5334 -0.2794) (xy 0.5334 -0.254) (xy 0.635 -0.254) (xy 0.635 0.254) (xy 0.5334 0.254) (xy 0.5334 0.2794)
				(xy -0.508 0.2794) (xy -0.5334 0.2794)
			)
			(stroke
				(width 0)
				(type default)
			)
			(fill no)
			(layer "F.CrtYd")
		)
		(pad "1" smd rect
			(at 0.40005 0)
			(size 0.4572 0.508)
			(layers "F.Cu" "F.Mask" "F.Paste")
			(net "P3V3_NODE1")
		)
		(pad "2" smd rect
			(at -0.40005 0)
			(size 0.4572 0.508)
			(layers "F.Cu" "F.Mask" "F.Paste")
			(net "GND")
		)
	)
	(footprint ""
		(layer "F.Cu")
		(at 90.81262 -167.41902 180)
		(property "Reference" "C581"
			(at -85.97392 -72.653652 0)
			(unlocked yes)
			(layer "F.SilkS")
			(effects
				(font
					(size 0.7874 0.5842)
					(thickness 0.1524)
				)
				(justify left)
			)
		)
		(property "Value" ""
			(at 0 0 180)
			(layer "F.Fab")
			(effects
				(font
					(size 1.27 1.27)
				)
			)
		)
		(duplicate_pad_numbers_are_jumpers no)
		(fp_line
			(start 0.7874 0.4064)
			(end -0.7874 0.4064)
			(stroke
				(width 0.1524)
				(type default)
			)
			(layer "F.SilkS")
		)
		(fp_line
			(start 0.7874 -0.4064)
			(end 0.7874 0.4064)
			(stroke
				(width 0.1524)
				(type default)
			)
			(layer "F.SilkS")
		)
		(fp_line
			(start 0 0.381)
			(end 0 -0.381)
			(stroke
				(width 0.1524)
				(type default)
			)
			(layer "F.SilkS")
		)
		(fp_line
			(start -0.7874 0.4064)
			(end -0.7874 -0.4064)
			(stroke
				(width 0.1524)
				(type default)
			)
			(layer "F.SilkS")
		)
		(fp_line
			(start -0.7874 -0.4064)
			(end 0.7874 -0.4064)
			(stroke
				(width 0.1524)
				(type default)
			)
			(layer "F.SilkS")
		)
		(fp_poly
			(pts
				(xy -0.5334 0.254) (xy -0.635 0.254) (xy -0.635 0.2286) (xy -0.635 -0.254) (xy -0.5334 -0.254) (xy -0.5334 -0.2794)
				(xy 0.5334 -0.2794) (xy 0.5334 -0.254) (xy 0.635 -0.254) (xy 0.635 0.254) (xy 0.5334 0.254) (xy 0.5334 0.2794)
				(xy -0.508 0.2794) (xy -0.5334 0.2794)
			)
			(stroke
				(width 0)
				(type default)
			)
			(fill no)
			(layer "F.CrtYd")
		)
		(pad "1" smd rect
			(at 0.40005 0 180)
			(size 0.4572 0.508)
			(layers "F.Cu" "F.Mask" "F.Paste")
			(net "P3V3_NODE1")
		)
		(pad "2" smd rect
			(at -0.40005 0 180)
			(size 0.4572 0.508)
			(layers "F.Cu" "F.Mask" "F.Paste")
			(net "GND")
		)
	)
	(footprint ""
		(layer "F.Cu")
		(at 105.191814 -106.89082 180)
		(property "Reference" "PC119"
			(at 5.923534 0.317754 0)
			(unlocked yes)
			(layer "F.SilkS")
			(effects
				(font
					(size 0.7874 0.5842)
					(thickness 0.1524)
				)
				(justify left)
			)
		)
		(property "Value" ""
			(at 0 0 180)
			(layer "F.Fab")
			(effects
				(font
					(size 1.27 1.27)
				)
			)
		)
		(duplicate_pad_numbers_are_jumpers no)
		(fp_line
			(start 1.905 0.8636)
			(end -1.905 0.8636)
			(stroke
				(width 0.1524)
				(type default)
			)
			(layer "F.SilkS")
		)
		(fp_line
			(start 1.905 -0.8636)
			(end 1.905 0.8636)
			(stroke
				(width 0.1524)
				(type default)
			)
			(layer "F.SilkS")
		)
		(fp_line
			(start 0 0.8382)
			(end 0 -0.8382)
			(stroke
				(width 0.1524)
				(type default)
			)
			(layer "F.SilkS")
		)
		(fp_line
			(start -1.905 0.8636)
			(end -1.905 -0.8636)
			(stroke
				(width 0.1524)
				(type default)
			)
			(layer "F.SilkS")
		)
		(fp_line
			(start -1.905 -0.8636)
			(end 1.905 -0.8636)
			(stroke
				(width 0.1524)
				(type default)
			)
			(layer "F.SilkS")
		)
		(fp_rect
			(start -1.524 0.7366)
			(end 1.524 -0.7366)
			(stroke
				(width 0)
				(type default)
			)
			(fill no)
			(layer "F.CrtYd")
		)
		(pad "1" smd rect
			(at 0.94996 0 180)
			(size 1.1176 1.3716)
			(layers "F.Cu" "F.Mask" "F.Paste")
			(net "GND")
		)
		(pad "2" smd rect
			(at -0.94996 0 180)
			(size 1.1176 1.3716)
			(layers "F.Cu" "F.Mask" "F.Paste")
			(net "PV_VCCP_NODE1")
		)
	)
)
